(kicad_pcb
	(version 20241229)
	(generator "pcbnew")
	(generator_version "9.0")
	(general
		(thickness 1.294)
		(legacy_teardrops no)
	)
	(paper "A3")
	(title_block
		(title "Kintex 410T devboard")
		(date "2024-04-03")
		(rev "1.1.2")
		(comment 9 "footprint 89 of 975 (J18), pads 1-92 of 564")
	)
	(layers
		(0 "F.Cu" mixed)
		(4 "In1.Cu" power)
		(6 "In2.Cu" power)
		(8 "In3.Cu" mixed)
		(10 "In4.Cu" power)
		(12 "In5.Cu" mixed)
		(14 "In6.Cu" power)
		(16 "In7.Cu" mixed)
		(18 "In8.Cu" power)
		(2 "B.Cu" mixed)
		(9 "F.Adhes" user "F.Adhesive")
		(11 "B.Adhes" user "B.Adhesive")
		(13 "F.Paste" user)
		(15 "B.Paste" user)
		(5 "F.SilkS" user "F.Silkscreen")
		(7 "B.SilkS" user "B.Silkscreen")
		(1 "F.Mask" user)
		(3 "B.Mask" user)
		(17 "Dwgs.User" user "User.Drawings")
		(19 "Cmts.User" user "User.Comments")
		(21 "Eco1.User" user "User.Eco1")
		(23 "Eco2.User" user "User.Eco2")
		(25 "Edge.Cuts" user)
		(27 "Margin" user)
		(31 "F.CrtYd" user "F.Courtyard")
		(29 "B.CrtYd" user "B.Courtyard")
		(35 "F.Fab" user)
		(33 "B.Fab" user)
	)
	(footprint "antmicro-footprints:ASP-184329-01_mounting_holes"
		(layer "F.Cu")
		(at 162.000001 106.000001 90)
		(property "Reference" "J18"
			(at 28.280001 4.299999 180)
			(layer "F.SilkS")
			(effects
				(font
					(size 0.7 0.7)
					(thickness 0.15)
				)
				(justify left bottom)
			)
		)
		(property "Value" "ASP-184329-01_mounting_holes"
			(at -8.4 0.2 90)
			(layer "F.Fab")
			(effects
				(font
					(size 0.7 0.7)
					(thickness 0.15)
				)
				(justify left bottom)
			)
		)
		(property "Description" "Mezzanine Connector, Array, Female, 1.27 mm, 14 Rows, 560 Contacts, Surface Mount"
			(at 0 0 90)
			(layer "F.Fab")
			(hide yes)
			(effects
				(font
					(size 1.27 1.27)
					(thickness 0.15)
				)
			)
		)
		(property "Author" "Antmicro"
			(at 268.000002 -56 0)
			(layer "F.Fab")
			(hide yes)
			(effects
				(font
					(size 1 1)
					(thickness 0.15)
				)
			)
		)
		(property "License" "Apache-2.0"
			(at 268.000002 -56 0)
			(layer "F.Fab")
			(hide yes)
			(effects
				(font
					(size 1 1)
					(thickness 0.15)
				)
			)
		)
		(property "MPN" "ASP-184329-01"
			(at 268.000002 -56 0)
			(layer "F.Fab")
			(hide yes)
			(effects
				(font
					(size 1 1)
					(thickness 0.15)
				)
			)
		)
		(property "Manufacturer" "Samtec"
			(at 268.000002 -56 0)
			(layer "F.Fab")
			(hide yes)
			(effects
				(font
					(size 1 1)
					(thickness 0.15)
				)
			)
		)
		(sheetname "FMC+ HSPC")
		(sheetfile "fmc-hspc.kicad_sch")
		(attr smd)
		(pad "" np_thru_hole circle
			(at -31.5 -2 90)
			(size 6 6)
			(drill 3.2)
			(layers "*.Cu" "*.Mask")
		)
		(pad "" np_thru_hole circle
			(at -27.191 0 90)
			(size 1.27 1.27)
			(drill 1.27)
			(layers "*.Cu" "*.Mask")
		)
		(pad "" np_thru_hole circle
			(at 27.19 3.048 90)
			(size 1.27 1.27)
			(drill 1.27)
			(layers "*.Cu" "*.Mask")
		)
		(pad "" np_thru_hole circle
			(at 31.499 -2 90)
			(size 6 6)
			(drill 3.2)
			(layers "*.Cu" "*.Mask")
		)
		(pad "A01" smd circle
			(at 24.765 5.714 90)
			(size 0.64 0.64)
			(layers "F.Cu" "F.Mask")
			(net 1 "GND")
			(pinfunction "GND")
			(pintype "passive")
		)
		(pad "A02" smd circle
			(at 23.495 5.714 90)
			(size 0.64 0.64)
			(layers "F.Cu" "F.Mask")
			(net 312 "/FMC+ HSPC/GTX116.RX2_P")
			(pinfunction "DP1_M2C_P")
			(pintype "passive")
		)
		(pad "A03" smd circle
			(at 22.225 5.714 90)
			(size 0.64 0.64)
			(layers "F.Cu" "F.Mask")
			(net 307 "/FMC+ HSPC/GTX116.RX2_N")
			(pinfunction "DP1_M2C_N")
			(pintype "passive")
		)
		(pad "A04" smd circle
			(at 20.954 5.714 90)
			(size 0.64 0.64)
			(layers "F.Cu" "F.Mask")
			(net 1 "GND")
			(pinfunction "GND")
			(pintype "passive")
		)
		(pad "A05" smd circle
			(at 19.684 5.714 90)
			(size 0.64 0.64)
			(layers "F.Cu" "F.Mask")
			(net 1 "GND")
			(pinfunction "GND")
			(pintype "passive")
		)
		(pad "A06" smd circle
			(at 18.414 5.714 90)
			(size 0.64 0.64)
			(layers "F.Cu" "F.Mask")
			(net 288 "/FMC+ HSPC/GTX116.RX1_P")
			(pinfunction "DP2_M2C_P")
			(pintype "passive")
		)
		(pad "A07" smd circle
			(at 17.144 5.714 90)
			(size 0.64 0.64)
			(layers "F.Cu" "F.Mask")
			(net 283 "/FMC+ HSPC/GTX116.RX1_N")
			(pinfunction "DP2_M2C_N")
			(pintype "passive")
		)
		(pad "A08" smd circle
			(at 15.874 5.714 90)
			(size 0.64 0.64)
			(layers "F.Cu" "F.Mask")
			(net 1 "GND")
			(pinfunction "GND")
			(pintype "passive")
		)
		(pad "A09" smd circle
			(at 14.605 5.714 90)
			(size 0.64 0.64)
			(layers "F.Cu" "F.Mask")
			(net 1 "GND")
			(pinfunction "GND")
			(pintype "passive")
		)
		(pad "A10" smd circle
			(at 13.335 5.714 90)
			(size 0.64 0.64)
			(layers "F.Cu" "F.Mask")
			(net 249 "/FMC+ HSPC/GTX116.RX0_P")
			(pinfunction "DP3_M2C_P")
			(pintype "passive")
		)
		(pad "A11" smd circle
			(at 12.063 5.714 90)
			(size 0.64 0.64)
			(layers "F.Cu" "F.Mask")
			(net 490 "/FMC+ HSPC/GTX116.RX0_N")
			(pinfunction "DP3_M2C_N")
			(pintype "passive")
		)
		(pad "A12" smd circle
			(at 10.794 5.714 90)
			(size 0.64 0.64)
			(layers "F.Cu" "F.Mask")
			(net 1 "GND")
			(pinfunction "GND")
			(pintype "passive")
		)
		(pad "A13" smd circle
			(at 9.525 5.714 90)
			(size 0.64 0.64)
			(layers "F.Cu" "F.Mask")
			(net 1 "GND")
			(pinfunction "GND")
			(pintype "passive")
		)
		(pad "A14" smd circle
			(at 8.255 5.714 90)
			(size 0.64 0.64)
			(layers "F.Cu" "F.Mask")
			(net 479 "/FMC+ HSPC/GTX115.RX3_P")
			(pinfunction "DP4_M2C_P")
			(pintype "passive")
		)
		(pad "A15" smd circle
			(at 6.985 5.714 90)
			(size 0.64 0.64)
			(layers "F.Cu" "F.Mask")
			(net 473 "/FMC+ HSPC/GTX115.RX3_N")
			(pinfunction "DP4_M2C_N")
			(pintype "passive")
		)
		(pad "A16" smd circle
			(at 5.714 5.714 90)
			(size 0.64 0.64)
			(layers "F.Cu" "F.Mask")
			(net 1 "GND")
			(pinfunction "GND")
			(pintype "passive")
		)
		(pad "A17" smd circle
			(at 4.445 5.714 90)
			(size 0.64 0.64)
			(layers "F.Cu" "F.Mask")
			(net 1 "GND")
			(pinfunction "GND")
			(pintype "passive")
		)
		(pad "A18" smd circle
			(at 3.173 5.714 90)
			(size 0.64 0.64)
			(layers "F.Cu" "F.Mask")
			(net 459 "/FMC+ HSPC/GTX115.RX2_P")
			(pinfunction "DP5_M2C_P")
			(pintype "passive")
		)
		(pad "A19" smd circle
			(at 1.904 5.714 90)
			(size 0.64 0.64)
			(layers "F.Cu" "F.Mask")
			(net 454 "/FMC+ HSPC/GTX115.RX2_N")
			(pinfunction "DP5_M2C_N")
			(pintype "passive")
		)
		(pad "A20" smd circle
			(at 0.633 5.714 90)
			(size 0.64 0.64)
			(layers "F.Cu" "F.Mask")
			(net 1 "GND")
			(pinfunction "GND")
			(pintype "passive")
		)
		(pad "A21" smd circle
			(at -0.635 5.714 90)
			(size 0.64 0.64)
			(layers "F.Cu" "F.Mask")
			(net 1 "GND")
			(pinfunction "GND")
			(pintype "passive")
		)
		(pad "A22" smd circle
			(at -1.905 5.714 90)
			(size 0.64 0.64)
			(layers "F.Cu" "F.Mask")
			(net 64 "/FMC+ HSPC/GTX_TX1_C_P")
			(pinfunction "DP1_C2M_P")
			(pintype "passive")
		)
		(pad "A23" smd circle
			(at -3.176 5.714 90)
			(size 0.64 0.64)
			(layers "F.Cu" "F.Mask")
			(net 67 "/FMC+ HSPC/GTX_TX1_C_N")
			(pinfunction "DP1_C2M_N")
			(pintype "passive")
		)
		(pad "A24" smd circle
			(at -4.446 5.714 90)
			(size 0.64 0.64)
			(layers "F.Cu" "F.Mask")
			(net 1 "GND")
			(pinfunction "GND")
			(pintype "passive")
		)
		(pad "A25" smd circle
			(at -5.715 5.714 90)
			(size 0.64 0.64)
			(layers "F.Cu" "F.Mask")
			(net 1 "GND")
			(pinfunction "GND")
			(pintype "passive")
		)
		(pad "A26" smd circle
			(at -6.986 5.714 90)
			(size 0.64 0.64)
			(layers "F.Cu" "F.Mask")
			(net 71 "/FMC+ HSPC/GTX_TX2_C_P")
			(pinfunction "DP2_C2M_P")
			(pintype "passive")
		)
		(pad "A27" smd circle
			(at -8.257 5.714 90)
			(size 0.64 0.64)
			(layers "F.Cu" "F.Mask")
			(net 76 "/FMC+ HSPC/GTX_TX2_C_N")
			(pinfunction "DP2_C2M_N")
			(pintype "passive")
		)
		(pad "A28" smd circle
			(at -9.526 5.714 90)
			(size 0.64 0.64)
			(layers "F.Cu" "F.Mask")
			(net 1 "GND")
			(pinfunction "GND")
			(pintype "passive")
		)
		(pad "A29" smd circle
			(at -10.795 5.714 90)
			(size 0.64 0.64)
			(layers "F.Cu" "F.Mask")
			(net 1 "GND")
			(pinfunction "GND")
			(pintype "passive")
		)
		(pad "A30" smd circle
			(at -12.065 5.714 90)
			(size 0.64 0.64)
			(layers "F.Cu" "F.Mask")
			(net 79 "/FMC+ HSPC/GTX_TX3_C_P")
			(pinfunction "DP3_C2M_P")
			(pintype "passive")
		)
		(pad "A31" smd circle
			(at -13.337 5.714 90)
			(size 0.64 0.64)
			(layers "F.Cu" "F.Mask")
			(net 81 "/FMC+ HSPC/GTX_TX3_C_N")
			(pinfunction "DP3_C2M_N")
			(pintype "passive")
		)
		(pad "A32" smd circle
			(at -14.606 5.714 90)
			(size 0.64 0.64)
			(layers "F.Cu" "F.Mask")
			(net 1 "GND")
			(pinfunction "GND")
			(pintype "passive")
		)
		(pad "A33" smd circle
			(at -15.875 5.714 90)
			(size 0.64 0.64)
			(layers "F.Cu" "F.Mask")
			(net 1 "GND")
			(pinfunction "GND")
			(pintype "passive")
		)
		(pad "A34" smd circle
			(at -17.145 5.714 90)
			(size 0.64 0.64)
			(layers "F.Cu" "F.Mask")
			(net 83 "/FMC+ HSPC/GTX_TX4_C_P")
			(pinfunction "DP4_C2M_P")
			(pintype "passive")
		)
		(pad "A35" smd circle
			(at -18.415 5.714 90)
			(size 0.64 0.64)
			(layers "F.Cu" "F.Mask")
			(net 88 "/FMC+ HSPC/GTX_TX4_C_N")
			(pinfunction "DP4_C2M_N")
			(pintype "passive")
		)
		(pad "A36" smd circle
			(at -19.685 5.714 90)
			(size 0.64 0.64)
			(layers "F.Cu" "F.Mask")
			(net 1 "GND")
			(pinfunction "GND")
			(pintype "passive")
		)
		(pad "A37" smd circle
			(at -20.956 5.714 90)
			(size 0.64 0.64)
			(layers "F.Cu" "F.Mask")
			(net 1 "GND")
			(pinfunction "GND")
			(pintype "passive")
		)
		(pad "A38" smd circle
			(at -22.226 5.714 90)
			(size 0.64 0.64)
			(layers "F.Cu" "F.Mask")
			(net 96 "/FMC+ HSPC/GTX_TX5_C_P")
			(pinfunction "DP5_C2M_P")
			(pintype "passive")
		)
		(pad "A39" smd circle
			(at -23.497 5.714 90)
			(size 0.64 0.64)
			(layers "F.Cu" "F.Mask")
			(net 98 "/FMC+ HSPC/GTX_TX5_C_N")
			(pinfunction "DP5_C2M_N")
			(pintype "passive")
		)
		(pad "A40" smd circle
			(at -24.767 5.714 90)
			(size 0.64 0.64)
			(layers "F.Cu" "F.Mask")
			(net 1 "GND")
			(pinfunction "GND")
			(pintype "passive")
		)
		(pad "B01" smd circle
			(at 24.765 4.445 90)
			(size 0.64 0.64)
			(layers "F.Cu" "F.Mask")
			(net 514 "/FMC+ HSPC/FMC.CLK_DIR")
			(pinfunction "CLK_DIR")
			(pintype "passive")
		)
		(pad "B02" smd circle
			(at 23.495 4.445 90)
			(size 0.64 0.64)
			(layers "F.Cu" "F.Mask")
			(net 1 "GND")
			(pinfunction "GND")
			(pintype "passive")
		)
		(pad "B03" smd circle
			(at 22.225 4.445 90)
			(size 0.64 0.64)
			(layers "F.Cu" "F.Mask")
			(net 1 "GND")
			(pinfunction "GND")
			(pintype "passive")
		)
		(pad "B04" smd circle
			(at 20.954 4.445 90)
			(size 0.64 0.64)
			(layers "F.Cu" "F.Mask")
			(net 50 "unconnected-(J18H-DP9_M2C_P-PadB04)")
			(pinfunction "DP9_M2C_P")
			(pintype "passive+no_connect")
		)
		(pad "B05" smd circle
			(at 19.684 4.445 90)
			(size 0.64 0.64)
			(layers "F.Cu" "F.Mask")
			(net 51 "unconnected-(J18H-DP9_M2C_N-PadB05)")
			(pinfunction "DP9_M2C_N")
			(pintype "passive+no_connect")
		)
		(pad "B06" smd circle
			(at 18.414 4.445 90)
			(size 0.64 0.64)
			(layers "F.Cu" "F.Mask")
			(net 1 "GND")
			(pinfunction "GND")
			(pintype "passive")
		)
		(pad "B07" smd circle
			(at 17.144 4.445 90)
			(size 0.64 0.64)
			(layers "F.Cu" "F.Mask")
			(net 1 "GND")
			(pinfunction "GND")
			(pintype "passive")
		)
		(pad "B08" smd circle
			(at 15.874 4.445 90)
			(size 0.64 0.64)
			(layers "F.Cu" "F.Mask")
			(net 52 "unconnected-(J18H-DP8_M2C_P-PadB08)")
			(pinfunction "DP8_M2C_P")
			(pintype "passive+no_connect")
		)
		(pad "B09" smd circle
			(at 14.605 4.445 90)
			(size 0.64 0.64)
			(layers "F.Cu" "F.Mask")
			(net 53 "unconnected-(J18H-DP8_M2C_N-PadB09)")
			(pinfunction "DP8_M2C_N")
			(pintype "passive+no_connect")
		)
		(pad "B10" smd circle
			(at 13.335 4.445 90)
			(size 0.64 0.64)
			(layers "F.Cu" "F.Mask")
			(net 1 "GND")
			(pinfunction "GND")
			(pintype "passive")
		)
		(pad "B11" smd circle
			(at 12.063 4.445 90)
			(size 0.64 0.64)
			(layers "F.Cu" "F.Mask")
			(net 1 "GND")
			(pinfunction "GND")
			(pintype "passive")
		)
		(pad "B12" smd circle
			(at 10.794 4.445 90)
			(size 0.64 0.64)
			(layers "F.Cu" "F.Mask")
			(net 486 "/FMC+ HSPC/GTX115.RX0_P")
			(pinfunction "DP7_M2C_P")
			(pintype "passive")
		)
		(pad "B13" smd circle
			(at 9.525 4.445 90)
			(size 0.64 0.64)
			(layers "F.Cu" "F.Mask")
			(net 483 "/FMC+ HSPC/GTX115.RX0_N")
			(pinfunction "DP7_M2C_N")
			(pintype "passive")
		)
		(pad "B14" smd circle
			(at 8.255 4.445 90)
			(size 0.64 0.64)
			(layers "F.Cu" "F.Mask")
			(net 1 "GND")
			(pinfunction "GND")
			(pintype "passive")
		)
		(pad "B15" smd circle
			(at 6.985 4.445 90)
			(size 0.64 0.64)
			(layers "F.Cu" "F.Mask")
			(net 1 "GND")
			(pinfunction "GND")
			(pintype "passive")
		)
		(pad "B16" smd circle
			(at 5.714 4.445 90)
			(size 0.64 0.64)
			(layers "F.Cu" "F.Mask")
			(net 468 "/FMC+ HSPC/GTX115.RX1_P")
			(pinfunction "DP6_M2C_P")
			(pintype "passive")
		)
		(pad "B17" smd circle
			(at 4.445 4.445 90)
			(size 0.64 0.64)
			(layers "F.Cu" "F.Mask")
			(net 463 "/FMC+ HSPC/GTX115.RX1_N")
			(pinfunction "DP6_M2C_N")
			(pintype "passive")
		)
		(pad "B18" smd circle
			(at 3.173 4.445 90)
			(size 0.64 0.64)
			(layers "F.Cu" "F.Mask")
			(net 1 "GND")
			(pinfunction "GND")
			(pintype "passive")
		)
		(pad "B19" smd circle
			(at 1.904 4.445 90)
			(size 0.64 0.64)
			(layers "F.Cu" "F.Mask")
			(net 1 "GND")
			(pinfunction "GND")
			(pintype "passive")
		)
		(pad "B20" smd circle
			(at 0.633 4.445 90)
			(size 0.64 0.64)
			(layers "F.Cu" "F.Mask")
			(net 499 "/FMC+ HSPC/GTR_REFCLK1_R_P")
			(pinfunction "GBTCLK1_M2C_P")
			(pintype "passive")
		)
		(pad "B21" smd circle
			(at -0.635 4.445 90)
			(size 0.64 0.64)
			(layers "F.Cu" "F.Mask")
			(net 478 "/FMC+ HSPC/GTR_REFCLK1_R_N")
			(pinfunction "GBTCLK1_M2C_N")
			(pintype "passive")
		)
		(pad "B22" smd circle
			(at -1.905 4.445 90)
			(size 0.64 0.64)
			(layers "F.Cu" "F.Mask")
			(net 1 "GND")
			(pinfunction "GND")
			(pintype "passive")
		)
		(pad "B23" smd circle
			(at -3.176 4.445 90)
			(size 0.64 0.64)
			(layers "F.Cu" "F.Mask")
			(net 1 "GND")
			(pinfunction "GND")
			(pintype "passive")
		)
		(pad "B24" smd circle
			(at -4.446 4.445 90)
			(size 0.64 0.64)
			(layers "F.Cu" "F.Mask")
			(net 57 "unconnected-(J18H-DP9_C2M_P-PadB24)")
			(pinfunction "DP9_C2M_P")
			(pintype "passive+no_connect")
		)
		(pad "B25" smd circle
			(at -5.715 4.445 90)
			(size 0.64 0.64)
			(layers "F.Cu" "F.Mask")
			(net 58 "unconnected-(J18H-DP9_C2M_N-PadB25)")
			(pinfunction "DP9_C2M_N")
			(pintype "passive+no_connect")
		)
		(pad "B26" smd circle
			(at -6.986 4.445 90)
			(size 0.64 0.64)
			(layers "F.Cu" "F.Mask")
			(net 1 "GND")
			(pinfunction "GND")
			(pintype "passive")
		)
		(pad "B27" smd circle
			(at -8.257 4.445 90)
			(size 0.64 0.64)
			(layers "F.Cu" "F.Mask")
			(net 1 "GND")
			(pinfunction "GND")
			(pintype "passive")
		)
		(pad "B28" smd circle
			(at -9.526 4.445 90)
			(size 0.64 0.64)
			(layers "F.Cu" "F.Mask")
			(net 66 "unconnected-(J18H-DP8_C2M_P-PadB28)")
			(pinfunction "DP8_C2M_P")
			(pintype "passive+no_connect")
		)
		(pad "B29" smd circle
			(at -10.795 4.445 90)
			(size 0.64 0.64)
			(layers "F.Cu" "F.Mask")
			(net 68 "unconnected-(J18H-DP8_C2M_N-PadB29)")
			(pinfunction "DP8_C2M_N")
			(pintype "passive+no_connect")
		)
		(pad "B30" smd circle
			(at -12.065 4.445 90)
			(size 0.64 0.64)
			(layers "F.Cu" "F.Mask")
			(net 1 "GND")
			(pinfunction "GND")
			(pintype "passive")
		)
		(pad "B31" smd circle
			(at -13.337 4.445 90)
			(size 0.64 0.64)
			(layers "F.Cu" "F.Mask")
			(net 1 "GND")
			(pinfunction "GND")
			(pintype "passive")
		)
		(pad "B32" smd circle
			(at -14.606 4.445 90)
			(size 0.64 0.64)
			(layers "F.Cu" "F.Mask")
			(net 119 "/FMC+ HSPC/GTX_TX7_C_P")
			(pinfunction "DP7_C2M_P")
			(pintype "passive")
		)
		(pad "B33" smd circle
			(at -15.875 4.445 90)
			(size 0.64 0.64)
			(layers "F.Cu" "F.Mask")
			(net 123 "/FMC+ HSPC/GTX_TX7_C_N")
			(pinfunction "DP7_C2M_N")
			(pintype "passive")
		)
		(pad "B34" smd circle
			(at -17.145 4.445 90)
			(size 0.64 0.64)
			(layers "F.Cu" "F.Mask")
			(net 1 "GND")
			(pinfunction "GND")
			(pintype "passive")
		)
		(pad "B35" smd circle
			(at -18.415 4.445 90)
			(size 0.64 0.64)
			(layers "F.Cu" "F.Mask")
			(net 1 "GND")
			(pinfunction "GND")
			(pintype "passive")
		)
		(pad "B36" smd circle
			(at -19.685 4.445 90)
			(size 0.64 0.64)
			(layers "F.Cu" "F.Mask")
			(net 105 "/FMC+ HSPC/GTX_TX6_C_P")
			(pinfunction "DP6_C2M_P")
			(pintype "passive")
		)
		(pad "B37" smd circle
			(at -20.956 4.445 90)
			(size 0.64 0.64)
			(layers "F.Cu" "F.Mask")
			(net 109 "/FMC+ HSPC/GTX_TX6_C_N")
			(pinfunction "DP6_C2M_N")
			(pintype "passive")
		)
		(pad "B38" smd circle
			(at -22.226 4.445 90)
			(size 0.64 0.64)
			(layers "F.Cu" "F.Mask")
			(net 1 "GND")
			(pinfunction "GND")
			(pintype "passive")
		)
		(pad "B39" smd circle
			(at -23.497 4.445 90)
			(size 0.64 0.64)
			(layers "F.Cu" "F.Mask")
			(net 1 "GND")
			(pinfunction "GND")
			(pintype "passive")
		)
		(pad "B40" smd circle
			(at -24.767 4.445 90)
			(size 0.64 0.64)
			(layers "F.Cu" "F.Mask")
			(net 70 "unconnected-(J18A-RES0-PadB40)")
			(pinfunction "RES0")
			(pintype "no_connect")
		)
		(pad "C01" smd circle
			(at 24.765 3.173 90)
			(size 0.64 0.64)
			(layers "F.Cu" "F.Mask")
			(net 1 "GND")
			(pinfunction "GND")
			(pintype "passive")
		)
		(pad "C02" smd circle
			(at 23.495 3.173 90)
			(size 0.64 0.64)
			(layers "F.Cu" "F.Mask")
			(net 60 "/FMC+ HSPC/GTX_TX0_C_P")
			(pinfunction "DP0_C2M_P")
			(pintype "passive")
		)
		(pad "C03" smd circle
			(at 22.225 3.173 90)
			(size 0.64 0.64)
			(layers "F.Cu" "F.Mask")
			(net 62 "/FMC+ HSPC/GTX_TX0_C_N")
			(pinfunction "DP0_C2M_N")
			(pintype "passive")
		)
		(pad "C04" smd circle
			(at 20.954 3.173 90)
			(size 0.64 0.64)
			(layers "F.Cu" "F.Mask")
			(net 1 "GND")
			(pinfunction "GND")
			(pintype "passive")
		)
		(pad "C05" smd circle
			(at 19.684 3.173 90)
			(size 0.64 0.64)
			(layers "F.Cu" "F.Mask")
			(net 1 "GND")
			(pinfunction "GND")
			(pintype "passive")
		)
		(pad "C06" smd circle
			(at 18.414 3.173 90)
			(size 0.64 0.64)
			(layers "F.Cu" "F.Mask")
			(net 287 "/FMC+ HSPC/GTX116.RX3_P")
			(pinfunction "DP0_M2C_P")
			(pintype "passive")
		)
		(pad "C07" smd circle
			(at 17.144 3.173 90)
			(size 0.64 0.64)
			(layers "F.Cu" "F.Mask")
			(net 282 "/FMC+ HSPC/GTX116.RX3_N")
			(pinfunction "DP0_M2C_N")
			(pintype "passive")
		)
		(pad "C08" smd circle
			(at 15.874 3.173 90)
			(size 0.64 0.64)
			(layers "F.Cu" "F.Mask")
			(net 1 "GND")
			(pinfunction "GND")
			(pintype "passive")
		)
	)
)
